# T6G (Grand Teton) — schematic netlist excerpt (pin names and nets, part order shuffled) for the footprints in the layout excerpt that follows; sources: Cadence DE-HDL packaged netlist, KiCad conversion of 04192023_DAF0TMB3IC0_F0TG_MB_C_brd_V02_OCP.brd

R6208  Q_RES  10K 1% CHIP  pkg 0402LF  page 176 : A = P5V_AUX ; B = USB_CPU0_HUB1_VBUS_US
PC2189  Q_CAP  0.01UF 50V 10% X7R  pkg C0402  page 262 : A = HSC_VSENSE ; B = AGND_HSC

(kicad_pcb
	(version 20260206)
	(generator "pcbnew")
	(generator_version "10.0")
	(general
		(thickness 1.6)
		(legacy_teardrops no)
	)
	(paper "A4")
	(title_block
		(title "04192023_DAF0TMB3IC0_F0TG_MB_C_brd_V02_OCP.brd")
		(comment 1 "Grand Teton / footprints 96-97 of 8354")
	)
	(layers
		(0 "F.Cu" signal "TOP")
		(4 "In1.Cu" signal "GND")
		(6 "In2.Cu" signal "IN1")
		(8 "In3.Cu" signal "GND1")
		(10 "In4.Cu" signal "IN2")
		(12 "In5.Cu" signal "GND2")
		(14 "In6.Cu" signal "IN3")
		(16 "In7.Cu" signal "GND3")
		(18 "In8.Cu" signal "VCC")
		(20 "In9.Cu" signal "VCC1")
		(22 "In10.Cu" signal "GND4")
		(24 "In11.Cu" signal "IN4")
		(26 "In12.Cu" signal "GND5")
		(28 "In13.Cu" signal "IN5")
		(30 "In14.Cu" signal "GND6")
		(32 "In15.Cu" signal "IN6")
		(34 "In16.Cu" signal "GND7")
		(2 "B.Cu" signal "BOTTOM")
		(9 "F.Adhes" user "F.Adhesive")
		(11 "B.Adhes" user "B.Adhesive")
		(13 "F.Paste" user "Package Geometry/Pastemask Top")
		(15 "B.Paste" user "Package Geometry/Pastemask Bottom")
		(5 "F.SilkS" user "Ref Des/Silkscreen Top")
		(7 "B.SilkS" user "Ref Des/Silkscreen Bottom")
		(1 "F.Mask" user "Board Geometry/Soldermask Top")
		(3 "B.Mask" user "Board Geometry/Soldermask Bottom")
		(17 "Dwgs.User" user "User.Drawings")
		(19 "Cmts.User" user "User.Comments")
		(21 "Eco1.User" user "User.Eco1")
		(23 "Eco2.User" user "User.Eco2")
		(25 "Edge.Cuts" user "Board Geometry/Outline")
		(27 "Margin" user)
		(31 "F.CrtYd" user "Package Geometry/Place Bound Top")
		(29 "B.CrtYd" user "Package Geometry/Place Bound Bottom")
		(35 "F.Fab" user "Ref Des/Assembly Top")
		(33 "B.Fab" user "Ref Des/Assembly Bottom")
	)
	(footprint ""
		(layer "F.Cu")
		(at 183.6547 -406.636982 90)
		(property "Reference" "PC2189"
			(at 0 0 90)
			(layer "F.SilkS")
			(hide yes)
			(effects
				(font
					(size 1.27 1.27)
				)
			)
		)
		(property "Value" ""
			(at 0 0 90)
			(layer "F.Fab")
			(effects
				(font
					(size 1.27 1.27)
				)
			)
		)
		(duplicate_pad_numbers_are_jumpers no)
		(fp_line
			(start 0.7874 -0.4064)
			(end 0.7874 0.4064)
			(stroke
				(width 0.1524)
				(type default)
			)
			(layer "F.SilkS")
		)
		(fp_line
			(start -0.7874 -0.4064)
			(end 0.7874 -0.4064)
			(stroke
				(width 0.1524)
				(type default)
			)
			(layer "F.SilkS")
		)
		(fp_line
			(start 0.7874 0.4064)
			(end -0.7874 0.4064)
			(stroke
				(width 0.1524)
				(type default)
			)
			(layer "F.SilkS")
		)
		(fp_line
			(start -0.7874 0.4064)
			(end -0.7874 -0.4064)
			(stroke
				(width 0.1524)
				(type default)
			)
			(layer "F.SilkS")
		)
		(fp_line
			(start -0.12065 -0.305054)
			(end -0.12065 -0.2794)
			(stroke
				(width 0.1)
				(type default)
			)
			(layer "F.Fab")
		)
		(fp_line
			(start -0.67945 -0.305054)
			(end -0.12065 -0.305054)
			(stroke
				(width 0.1)
				(type default)
			)
			(layer "F.Fab")
		)
		(fp_line
			(start 0.67945 -0.3048)
			(end 0.67945 0.3048)
			(stroke
				(width 0.1)
				(type default)
			)
			(layer "F.Fab")
		)
		(fp_line
			(start 0.12065 -0.3048)
			(end 0.67945 -0.3048)
			(stroke
				(width 0.1)
				(type default)
			)
			(layer "F.Fab")
		)
		(fp_line
			(start 0.12065 -0.2794)
			(end 0.12065 -0.3048)
			(stroke
				(width 0.1)
				(type default)
			)
			(layer "F.Fab")
		)
		(fp_line
			(start -0.12065 -0.2794)
			(end 0.12065 -0.2794)
			(stroke
				(width 0.1)
				(type default)
			)
			(layer "F.Fab")
		)
		(fp_line
			(start 0.120396 0.2794)
			(end -0.12065 0.2794)
			(stroke
				(width 0.1)
				(type default)
			)
			(layer "F.Fab")
		)
		(fp_line
			(start -0.12065 0.2794)
			(end -0.12065 0.3048)
			(stroke
				(width 0.1)
				(type default)
			)
			(layer "F.Fab")
		)
		(fp_line
			(start 0.67945 0.3048)
			(end 0.120396 0.3048)
			(stroke
				(width 0.1)
				(type default)
			)
			(layer "F.Fab")
		)
		(fp_line
			(start 0.120396 0.3048)
			(end 0.120396 0.2794)
			(stroke
				(width 0.1)
				(type default)
			)
			(layer "F.Fab")
		)
		(fp_line
			(start -0.12065 0.3048)
			(end -0.67945 0.3048)
			(stroke
				(width 0.1)
				(type default)
			)
			(layer "F.Fab")
		)
		(fp_line
			(start -0.67945 0.3048)
			(end -0.67945 -0.305054)
			(stroke
				(width 0.1)
				(type default)
			)
			(layer "F.Fab")
		)
		(pad "1" smd circle
			(at -0.40005 0 90)
			(size 0 0)
			(layers "F.Cu" "F.Mask" "F.Paste")
			(net "HSC_VSENSE")
		)
		(pad "2" smd circle
			(at 0.40005 0 90)
			(size 0 0)
			(layers "F.Cu" "F.Mask" "F.Paste")
			(net "AGND_HSC")
		)
	)
	(footprint ""
		(layer "F.Cu")
		(at 140.420344 -39.793418 180)
		(property "Reference" "R6208"
			(at 0 0 180)
			(layer "F.SilkS")
			(hide yes)
			(effects
				(font
					(size 1.27 1.27)
				)
			)
		)
		(property "Value" ""
			(at 0 0 180)
			(layer "F.Fab")
			(effects
				(font
					(size 1.27 1.27)
				)
			)
		)
		(duplicate_pad_numbers_are_jumpers no)
		(fp_line
			(start 0.7874 0.4064)
			(end -0.7874 0.4064)
			(stroke
				(width 0.1524)
				(type default)
			)
			(layer "F.SilkS")
		)
		(fp_line
			(start 0.7874 -0.4064)
			(end 0.7874 0.4064)
			(stroke
				(width 0.1524)
				(type default)
			)
			(layer "F.SilkS")
		)
		(fp_line
			(start -0.7874 0.4064)
			(end -0.7874 -0.4064)
			(stroke
				(width 0.1524)
				(type default)
			)
			(layer "F.SilkS")
		)
		(fp_line
			(start -0.7874 -0.4064)
			(end 0.7874 -0.4064)
			(stroke
				(width 0.1524)
				(type default)
			)
			(layer "F.SilkS")
		)
		(fp_line
			(start 0.67945 0.3048)
			(end 0.120396 0.3048)
			(stroke
				(width 0.1)
				(type default)
			)
			(layer "F.Fab")
		)
		(fp_line
			(start 0.67945 -0.3048)
			(end 0.67945 0.3048)
			(stroke
				(width 0.1)
				(type default)
			)
			(layer "F.Fab")
		)
		(fp_line
			(start 0.12065 -0.2794)
			(end 0.12065 -0.3048)
			(stroke
				(width 0.1)
				(type default)
			)
			(layer "F.Fab")
		)
		(fp_line
			(start 0.12065 -0.3048)
			(end 0.67945 -0.3048)
			(stroke
				(width 0.1)
				(type default)
			)
			(layer "F.Fab")
		)
		(fp_line
			(start 0.120396 0.3048)
			(end 0.120396 0.2794)
			(stroke
				(width 0.1)
				(type default)
			)
			(layer "F.Fab")
		)
		(fp_line
			(start 0.120396 0.2794)
			(end -0.12065 0.2794)
			(stroke
				(width 0.1)
				(type default)
			)
			(layer "F.Fab")
		)
		(fp_line
			(start -0.12065 0.3048)
			(end -0.67945 0.3048)
			(stroke
				(width 0.1)
				(type default)
			)
			(layer "F.Fab")
		)
		(fp_line
			(start -0.12065 0.2794)
			(end -0.12065 0.3048)
			(stroke
				(width 0.1)
				(type default)
			)
			(layer "F.Fab")
		)
		(fp_line
			(start -0.12065 -0.2794)
			(end 0.12065 -0.2794)
			(stroke
				(width 0.1)
				(type default)
			)
			(layer "F.Fab")
		)
		(fp_line
			(start -0.12065 -0.305054)
			(end -0.12065 -0.2794)
			(stroke
				(width 0.1)
				(type default)
			)
			(layer "F.Fab")
		)
		(fp_line
			(start -0.67945 0.3048)
			(end -0.67945 -0.305054)
			(stroke
				(width 0.1)
				(type default)
			)
			(layer "F.Fab")
		)
		(fp_line
			(start -0.67945 -0.305054)
			(end -0.12065 -0.305054)
			(stroke
				(width 0.1)
				(type default)
			)
			(layer "F.Fab")
		)
		(pad "1" smd circle
			(at -0.40005 0 180)
			(size 0 0)
			(layers "F.Cu" "F.Mask" "F.Paste")
			(net "P5V_AUX")
		)
		(pad "2" smd circle
			(at 0.40005 0 180)
			(size 0 0)
			(layers "F.Cu" "F.Mask" "F.Paste")
			(net "USB_CPU0_HUB1_VBUS_US")
		)
	)
)
